(kicad_pcb
	(version 20260206)
	(generator "pcbnew")
	(generator_version "10.0")
	(general
		(thickness 1.6)
		(legacy_teardrops no)
	)
	(paper "A4")
	(title_block
		(title "04192023_DAF0TMB3IC0_F0TG_MB_C_brd_V02_OCP.brd")
		(comment 1 "Grand Teton / footprints 2416-2416 of 8354")
	)
	(layers
		(0 "F.Cu" signal "TOP")
		(4 "In1.Cu" signal "GND")
		(6 "In2.Cu" signal "IN1")
		(8 "In3.Cu" signal "GND1")
		(10 "In4.Cu" signal "IN2")
		(12 "In5.Cu" signal "GND2")
		(14 "In6.Cu" signal "IN3")
		(16 "In7.Cu" signal "GND3")
		(18 "In8.Cu" signal "VCC")
		(20 "In9.Cu" signal "VCC1")
		(22 "In10.Cu" signal "GND4")
		(24 "In11.Cu" signal "IN4")
		(26 "In12.Cu" signal "GND5")
		(28 "In13.Cu" signal "IN5")
		(30 "In14.Cu" signal "GND6")
		(32 "In15.Cu" signal "IN6")
		(34 "In16.Cu" signal "GND7")
		(2 "B.Cu" signal "BOTTOM")
		(9 "F.Adhes" user "F.Adhesive")
		(11 "B.Adhes" user "B.Adhesive")
		(13 "F.Paste" user "Package Geometry/Pastemask Top")
		(15 "B.Paste" user "Package Geometry/Pastemask Bottom")
		(5 "F.SilkS" user "Ref Des/Silkscreen Top")
		(7 "B.SilkS" user "Ref Des/Silkscreen Bottom")
		(1 "F.Mask" user "Board Geometry/Soldermask Top")
		(3 "B.Mask" user "Board Geometry/Soldermask Bottom")
		(17 "Dwgs.User" user "User.Drawings")
		(19 "Cmts.User" user "User.Comments")
		(21 "Eco1.User" user "User.Eco1")
		(23 "Eco2.User" user "User.Eco2")
		(25 "Edge.Cuts" user "Board Geometry/Outline")
		(27 "Margin" user)
		(31 "F.CrtYd" user "Package Geometry/Place Bound Top")
		(29 "B.CrtYd" user "Package Geometry/Place Bound Bottom")
		(35 "F.Fab" user "Ref Des/Assembly Top")
		(33 "B.Fab" user "Ref Des/Assembly Bottom")
	)
	(footprint ""
		(layer "F.Cu")
		(at 177.397918 -424.283632)
		(property "Reference" "R2983"
			(at 0 0 0)
			(layer "F.SilkS")
			(hide yes)
			(effects
				(font
					(size 1.27 1.27)
				)
			)
		)
		(property "Value" ""
			(at 0 0 0)
			(layer "F.Fab")
			(effects
				(font
					(size 1.27 1.27)
				)
			)
		)
		(duplicate_pad_numbers_are_jumpers no)
		(fp_line
			(start -0.7874 -0.4064)
			(end 0.7874 -0.4064)
			(stroke
				(width 0.1524)
				(type default)
			)
			(layer "F.SilkS")
		)
		(fp_line
			(start -0.7874 0.4064)
			(end -0.7874 -0.4064)
			(stroke
				(width 0.1524)
				(type default)
			)
			(layer "F.SilkS")
		)
		(fp_line
			(start 0.7874 -0.4064)
			(end 0.7874 0.4064)
			(stroke
				(width 0.1524)
				(type default)
			)
			(layer "F.SilkS")
		)
		(fp_line
			(start 0.7874 0.4064)
			(end -0.7874 0.4064)
			(stroke
				(width 0.1524)
				(type default)
			)
			(layer "F.SilkS")
		)
		(fp_line
			(start -0.67945 -0.305054)
			(end -0.12065 -0.305054)
			(stroke
				(width 0.1)
				(type default)
			)
			(layer "F.Fab")
		)
		(fp_line
			(start -0.67945 0.3048)
			(end -0.67945 -0.305054)
			(stroke
				(width 0.1)
				(type default)
			)
			(layer "F.Fab")
		)
		(fp_line
			(start -0.12065 -0.305054)
			(end -0.12065 -0.2794)
			(stroke
				(width 0.1)
				(type default)
			)
			(layer "F.Fab")
		)
		(fp_line
			(start -0.12065 -0.2794)
			(end 0.12065 -0.2794)
			(stroke
				(width 0.1)
				(type default)
			)
			(layer "F.Fab")
		)
		(fp_line
			(start -0.12065 0.2794)
			(end -0.12065 0.3048)
			(stroke
				(width 0.1)
				(type default)
			)
			(layer "F.Fab")
		)
		(fp_line
			(start -0.12065 0.3048)
			(end -0.67945 0.3048)
			(stroke
				(width 0.1)
				(type default)
			)
			(layer "F.Fab")
		)
		(fp_line
			(start 0.120396 0.2794)
			(end -0.12065 0.2794)
			(stroke
				(width 0.1)
				(type default)
			)
			(layer "F.Fab")
		)
		(fp_line
			(start 0.120396 0.3048)
			(end 0.120396 0.2794)
			(stroke
				(width 0.1)
				(type default)
			)
			(layer "F.Fab")
		)
		(fp_line
			(start 0.12065 -0.3048)
			(end 0.67945 -0.3048)
			(stroke
				(width 0.1)
				(type default)
			)
			(layer "F.Fab")
		)
		(fp_line
			(start 0.12065 -0.2794)
			(end 0.12065 -0.3048)
			(stroke
				(width 0.1)
				(type default)
			)
			(layer "F.Fab")
		)
		(fp_line
			(start 0.67945 -0.3048)
			(end 0.67945 0.3048)
			(stroke
				(width 0.1)
				(type default)
			)
			(layer "F.Fab")
		)
		(fp_line
			(start 0.67945 0.3048)
			(end 0.120396 0.3048)
			(stroke
				(width 0.1)
				(type default)
			)
			(layer "F.Fab")
		)
		(pad "1" smd circle
			(at -0.40005 0)
			(size 0 0)
			(layers "F.Cu" "F.Mask" "F.Paste")
			(net "SMB_IOEXP_3V3AUX_SDA")
		)
		(pad "2" smd circle
			(at 0.40005 0)
			(size 0 0)
			(layers "F.Cu" "F.Mask" "F.Paste")
			(net "SMB_IOEXP_3V3AUX_SDA_R1")
		)
	)
)
